# T6G (Grand Teton) — schematic netlist excerpt (pin names and nets, part order shuffled) for the footprints in the layout excerpt that follows; sources: Cadence DE-HDL packaged netlist, KiCad conversion of 04192023_DAF0TMB3IC0_F0TG_MB_C_brd_V02_OCP.brd

R4266  Q_RES  33.2 1% CHIP  pkg 0402LF  page 241 : A = PWRGD_P3V3_AUX_PDB_BUF_R ; B = PWRGD_P3V3_AUX_PDB_BUF
R1499  Q_RES  4.7K 5% EMPTY  pkg 0201LF  page 342 : A = P1V8_CPU1_RT_1D ; B = JTAG_TCK_RT_CPU1_P2
PR3842  Q_RES  10K 1% CHIP  pkg 0402LF  page 135 : A = P12V_OCP_OV_FB_1 ; B = GND

(kicad_pcb
	(version 20260206)
	(generator "pcbnew")
	(generator_version "10.0")
	(general
		(thickness 1.6)
		(legacy_teardrops no)
	)
	(paper "A4")
	(title_block
		(title "04192023_DAF0TMB3IC0_F0TG_MB_C_brd_V02_OCP.brd")
		(comment 1 "Grand Teton / footprints 3956-3958 of 8354")
	)
	(layers
		(0 "F.Cu" signal "TOP")
		(4 "In1.Cu" signal "GND")
		(6 "In2.Cu" signal "IN1")
		(8 "In3.Cu" signal "GND1")
		(10 "In4.Cu" signal "IN2")
		(12 "In5.Cu" signal "GND2")
		(14 "In6.Cu" signal "IN3")
		(16 "In7.Cu" signal "GND3")
		(18 "In8.Cu" signal "VCC")
		(20 "In9.Cu" signal "VCC1")
		(22 "In10.Cu" signal "GND4")
		(24 "In11.Cu" signal "IN4")
		(26 "In12.Cu" signal "GND5")
		(28 "In13.Cu" signal "IN5")
		(30 "In14.Cu" signal "GND6")
		(32 "In15.Cu" signal "IN6")
		(34 "In16.Cu" signal "GND7")
		(2 "B.Cu" signal "BOTTOM")
		(9 "F.Adhes" user "F.Adhesive")
		(11 "B.Adhes" user "B.Adhesive")
		(13 "F.Paste" user "Package Geometry/Pastemask Top")
		(15 "B.Paste" user "Package Geometry/Pastemask Bottom")
		(5 "F.SilkS" user "Ref Des/Silkscreen Top")
		(7 "B.SilkS" user "Ref Des/Silkscreen Bottom")
		(1 "F.Mask" user "Board Geometry/Soldermask Top")
		(3 "B.Mask" user "Board Geometry/Soldermask Bottom")
		(17 "Dwgs.User" user "User.Drawings")
		(19 "Cmts.User" user "User.Comments")
		(21 "Eco1.User" user "User.Eco1")
		(23 "Eco2.User" user "User.Eco2")
		(25 "Edge.Cuts" user "Board Geometry/Outline")
		(27 "Margin" user)
		(31 "F.CrtYd" user "Package Geometry/Place Bound Top")
		(29 "B.CrtYd" user "Package Geometry/Place Bound Bottom")
		(35 "F.Fab" user "Ref Des/Assembly Top")
		(33 "B.Fab" user "Ref Des/Assembly Bottom")
	)
	(footprint ""
		(layer "F.Cu")
		(at 277.650956 -428.556166 180)
		(property "Reference" "R4266"
			(at 0 0 180)
			(layer "F.SilkS")
			(hide yes)
			(effects
				(font
					(size 1.27 1.27)
				)
			)
		)
		(property "Value" ""
			(at 0 0 180)
			(layer "F.Fab")
			(effects
				(font
					(size 1.27 1.27)
				)
			)
		)
		(duplicate_pad_numbers_are_jumpers no)
		(fp_line
			(start 0.7874 0.4064)
			(end -0.7874 0.4064)
			(stroke
				(width 0.1524)
				(type default)
			)
			(layer "F.SilkS")
		)
		(fp_line
			(start 0.7874 -0.4064)
			(end 0.7874 0.4064)
			(stroke
				(width 0.1524)
				(type default)
			)
			(layer "F.SilkS")
		)
		(fp_line
			(start -0.7874 0.4064)
			(end -0.7874 -0.4064)
			(stroke
				(width 0.1524)
				(type default)
			)
			(layer "F.SilkS")
		)
		(fp_line
			(start -0.7874 -0.4064)
			(end 0.7874 -0.4064)
			(stroke
				(width 0.1524)
				(type default)
			)
			(layer "F.SilkS")
		)
		(fp_line
			(start 0.67945 0.3048)
			(end 0.120396 0.3048)
			(stroke
				(width 0.1)
				(type default)
			)
			(layer "F.Fab")
		)
		(fp_line
			(start 0.67945 -0.3048)
			(end 0.67945 0.3048)
			(stroke
				(width 0.1)
				(type default)
			)
			(layer "F.Fab")
		)
		(fp_line
			(start 0.12065 -0.2794)
			(end 0.12065 -0.3048)
			(stroke
				(width 0.1)
				(type default)
			)
			(layer "F.Fab")
		)
		(fp_line
			(start 0.12065 -0.3048)
			(end 0.67945 -0.3048)
			(stroke
				(width 0.1)
				(type default)
			)
			(layer "F.Fab")
		)
		(fp_line
			(start 0.120396 0.3048)
			(end 0.120396 0.2794)
			(stroke
				(width 0.1)
				(type default)
			)
			(layer "F.Fab")
		)
		(fp_line
			(start 0.120396 0.2794)
			(end -0.12065 0.2794)
			(stroke
				(width 0.1)
				(type default)
			)
			(layer "F.Fab")
		)
		(fp_line
			(start -0.12065 0.3048)
			(end -0.67945 0.3048)
			(stroke
				(width 0.1)
				(type default)
			)
			(layer "F.Fab")
		)
		(fp_line
			(start -0.12065 0.2794)
			(end -0.12065 0.3048)
			(stroke
				(width 0.1)
				(type default)
			)
			(layer "F.Fab")
		)
		(fp_line
			(start -0.12065 -0.2794)
			(end 0.12065 -0.2794)
			(stroke
				(width 0.1)
				(type default)
			)
			(layer "F.Fab")
		)
		(fp_line
			(start -0.12065 -0.305054)
			(end -0.12065 -0.2794)
			(stroke
				(width 0.1)
				(type default)
			)
			(layer "F.Fab")
		)
		(fp_line
			(start -0.67945 0.3048)
			(end -0.67945 -0.305054)
			(stroke
				(width 0.1)
				(type default)
			)
			(layer "F.Fab")
		)
		(fp_line
			(start -0.67945 -0.305054)
			(end -0.12065 -0.305054)
			(stroke
				(width 0.1)
				(type default)
			)
			(layer "F.Fab")
		)
		(pad "1" smd circle
			(at -0.40005 0 180)
			(size 0 0)
			(layers "F.Cu" "F.Mask" "F.Paste")
			(net "PWRGD_P3V3_AUX_PDB_BUF_R")
		)
		(pad "2" smd circle
			(at 0.40005 0 180)
			(size 0 0)
			(layers "F.Cu" "F.Mask" "F.Paste")
			(net "PWRGD_P3V3_AUX_PDB_BUF")
		)
	)
	(footprint ""
		(layer "F.Cu")
		(at 177.81016 -394.1318)
		(property "Reference" "R1499"
			(at 0 0 0)
			(layer "F.SilkS")
			(hide yes)
			(effects
				(font
					(size 1.27 1.27)
				)
			)
		)
		(property "Value" ""
			(at 0 0 0)
			(layer "F.Fab")
			(effects
				(font
					(size 1.27 1.27)
				)
			)
		)
		(duplicate_pad_numbers_are_jumpers no)
		(fp_line
			(start -0.32512 -0.175006)
			(end 0.32512 -0.175006)
			(stroke
				(width 0.1)
				(type default)
			)
			(layer "F.Fab")
		)
		(fp_line
			(start -0.32512 0.175006)
			(end -0.32512 -0.175006)
			(stroke
				(width 0.1)
				(type default)
			)
			(layer "F.Fab")
		)
		(fp_line
			(start 0.32512 -0.175006)
			(end 0.32512 0.175006)
			(stroke
				(width 0.1)
				(type default)
			)
			(layer "F.Fab")
		)
		(fp_line
			(start 0.32512 0.175006)
			(end -0.32512 0.175006)
			(stroke
				(width 0.1)
				(type default)
			)
			(layer "F.Fab")
		)
		(pad "1" smd rect
			(at -0.2667 0)
			(size 0.3048 0.381)
			(layers "F.Cu" "F.Mask" "F.Paste")
			(net "P1V8_CPU1_RT_1D")
		)
		(pad "2" smd rect
			(at 0.2667 0 180)
			(size 0.3048 0.381)
			(layers "F.Cu" "F.Mask" "F.Paste")
			(net "JTAG_TCK_RT_CPU1_P2")
		)
	)
	(footprint ""
		(layer "F.Cu")
		(at 438.558432 -27.275536 -90)
		(property "Reference" "PR3842"
			(at 0 0 270)
			(layer "F.SilkS")
			(hide yes)
			(effects
				(font
					(size 1.27 1.27)
				)
			)
		)
		(property "Value" ""
			(at 0 0 270)
			(layer "F.Fab")
			(effects
				(font
					(size 1.27 1.27)
				)
			)
		)
		(duplicate_pad_numbers_are_jumpers no)
		(fp_line
			(start -0.7874 0.4064)
			(end -0.7874 -0.4064)
			(stroke
				(width 0.1524)
				(type default)
			)
			(layer "F.SilkS")
		)
		(fp_line
			(start 0.7874 0.4064)
			(end -0.7874 0.4064)
			(stroke
				(width 0.1524)
				(type default)
			)
			(layer "F.SilkS")
		)
		(fp_line
			(start -0.7874 -0.4064)
			(end 0.7874 -0.4064)
			(stroke
				(width 0.1524)
				(type default)
			)
			(layer "F.SilkS")
		)
		(fp_line
			(start 0.7874 -0.4064)
			(end 0.7874 0.4064)
			(stroke
				(width 0.1524)
				(type default)
			)
			(layer "F.SilkS")
		)
		(fp_line
			(start -0.67945 0.3048)
			(end -0.67945 -0.305054)
			(stroke
				(width 0.1)
				(type default)
			)
			(layer "F.Fab")
		)
		(fp_line
			(start -0.12065 0.3048)
			(end -0.67945 0.3048)
			(stroke
				(width 0.1)
				(type default)
			)
			(layer "F.Fab")
		)
		(fp_line
			(start 0.120396 0.3048)
			(end 0.120396 0.2794)
			(stroke
				(width 0.1)
				(type default)
			)
			(layer "F.Fab")
		)
		(fp_line
			(start 0.67945 0.3048)
			(end 0.120396 0.3048)
			(stroke
				(width 0.1)
				(type default)
			)
			(layer "F.Fab")
		)
		(fp_line
			(start -0.12065 0.2794)
			(end -0.12065 0.3048)
			(stroke
				(width 0.1)
				(type default)
			)
			(layer "F.Fab")
		)
		(fp_line
			(start 0.120396 0.2794)
			(end -0.12065 0.2794)
			(stroke
				(width 0.1)
				(type default)
			)
			(layer "F.Fab")
		)
		(fp_line
			(start -0.12065 -0.2794)
			(end 0.12065 -0.2794)
			(stroke
				(width 0.1)
				(type default)
			)
			(layer "F.Fab")
		)
		(fp_line
			(start 0.12065 -0.2794)
			(end 0.12065 -0.3048)
			(stroke
				(width 0.1)
				(type default)
			)
			(layer "F.Fab")
		)
		(fp_line
			(start 0.12065 -0.3048)
			(end 0.67945 -0.3048)
			(stroke
				(width 0.1)
				(type default)
			)
			(layer "F.Fab")
		)
		(fp_line
			(start 0.67945 -0.3048)
			(end 0.67945 0.3048)
			(stroke
				(width 0.1)
				(type default)
			)
			(layer "F.Fab")
		)
		(fp_line
			(start -0.67945 -0.305054)
			(end -0.12065 -0.305054)
			(stroke
				(width 0.1)
				(type default)
			)
			(layer "F.Fab")
		)
		(fp_line
			(start -0.12065 -0.305054)
			(end -0.12065 -0.2794)
			(stroke
				(width 0.1)
				(type default)
			)
			(layer "F.Fab")
		)
		(pad "1" smd circle
			(at -0.40005 0 270)
			(size 0 0)
			(layers "F.Cu" "F.Mask" "F.Paste")
			(net "P12V_OCP_OV_FB_1")
		)
		(pad "2" smd circle
			(at 0.40005 0 270)
			(size 0 0)
			(layers "F.Cu" "F.Mask" "F.Paste")
			(net "GND")
		)
	)
)
